(kicad_pcb
	(version 20260206)
	(generator "pcbnew")
	(generator_version "10.0")
	(general
		(thickness 1.6)
		(legacy_teardrops no)
	)
	(paper "A4")
	(title_block
		(title "01162023_DA0F0TEBIF0_F0T_Expander_BD_F_brd_V02_OCP.brd")
		(comment 1 "Grand Teton / footprints 5679-5684 of 9728")
	)
	(layers
		(0 "F.Cu" signal "TOP")
		(4 "In1.Cu" signal "GND")
		(6 "In2.Cu" signal "VCC")
		(8 "In3.Cu" signal "VCC1")
		(10 "In4.Cu" signal "GND1")
		(12 "In5.Cu" signal "IN1")
		(14 "In6.Cu" signal "GND2")
		(16 "In7.Cu" signal "IN2")
		(18 "In8.Cu" signal "GND3")
		(20 "In9.Cu" signal "IN3")
		(22 "In10.Cu" signal "GND4")
		(24 "In11.Cu" signal "IN4")
		(26 "In12.Cu" signal "GND5")
		(28 "In13.Cu" signal "IN5")
		(30 "In14.Cu" signal "GND6")
		(32 "In15.Cu" signal "IN6")
		(34 "In16.Cu" signal "GND7")
		(2 "B.Cu" signal "BOTTOM")
		(9 "F.Adhes" user "F.Adhesive")
		(11 "B.Adhes" user "B.Adhesive")
		(13 "F.Paste" user "Package Geometry/Pastemask Top")
		(15 "B.Paste" user "Package Geometry/Pastemask Bottom")
		(5 "F.SilkS" user "Ref Des/Silkscreen Top")
		(7 "B.SilkS" user "Ref Des/Silkscreen Bottom")
		(1 "F.Mask" user "Board Geometry/Soldermask Top")
		(3 "B.Mask" user "Board Geometry/Soldermask Bottom")
		(17 "Dwgs.User" user "User.Drawings")
		(19 "Cmts.User" user "User.Comments")
		(21 "Eco1.User" user "User.Eco1")
		(23 "Eco2.User" user "User.Eco2")
		(25 "Edge.Cuts" user "Board Geometry/Outline")
		(27 "Margin" user)
		(31 "F.CrtYd" user "Package Geometry/Place Bound Top")
		(29 "B.CrtYd" user "Package Geometry/Place Bound Bottom")
		(35 "F.Fab" user "Ref Des/Assembly Top")
		(33 "B.Fab" user "Ref Des/Assembly Bottom")
	)
	(footprint ""
		(layer "F.Cu")
		(at 338.582 -205.232 -90)
		(property "Reference" "R4126"
			(at 0 0 270)
			(layer "F.SilkS")
			(hide yes)
			(effects
				(font
					(size 1.27 1.27)
				)
			)
		)
		(property "Value" ""
			(at 0 0 270)
			(layer "F.Fab")
			(effects
				(font
					(size 1.27 1.27)
				)
			)
		)
		(duplicate_pad_numbers_are_jumpers no)
		(fp_line
			(start -0.7874 0.4064)
			(end -0.7874 -0.4064)
			(stroke
				(width 0.1524)
				(type default)
			)
			(layer "F.SilkS")
		)
		(fp_line
			(start 0.7874 0.4064)
			(end -0.7874 0.4064)
			(stroke
				(width 0.1524)
				(type default)
			)
			(layer "F.SilkS")
		)
		(fp_line
			(start -0.7874 -0.4064)
			(end 0.7874 -0.4064)
			(stroke
				(width 0.1524)
				(type default)
			)
			(layer "F.SilkS")
		)
		(fp_line
			(start 0.7874 -0.4064)
			(end 0.7874 0.4064)
			(stroke
				(width 0.1524)
				(type default)
			)
			(layer "F.SilkS")
		)
		(fp_line
			(start -0.67945 0.3048)
			(end -0.67945 -0.305054)
			(stroke
				(width 0.1)
				(type default)
			)
			(layer "F.Fab")
		)
		(fp_line
			(start -0.12065 0.3048)
			(end -0.67945 0.3048)
			(stroke
				(width 0.1)
				(type default)
			)
			(layer "F.Fab")
		)
		(fp_line
			(start 0.120396 0.3048)
			(end 0.120396 0.2794)
			(stroke
				(width 0.1)
				(type default)
			)
			(layer "F.Fab")
		)
		(fp_line
			(start 0.67945 0.3048)
			(end 0.120396 0.3048)
			(stroke
				(width 0.1)
				(type default)
			)
			(layer "F.Fab")
		)
		(fp_line
			(start -0.12065 0.2794)
			(end -0.12065 0.3048)
			(stroke
				(width 0.1)
				(type default)
			)
			(layer "F.Fab")
		)
		(fp_line
			(start 0.120396 0.2794)
			(end -0.12065 0.2794)
			(stroke
				(width 0.1)
				(type default)
			)
			(layer "F.Fab")
		)
		(fp_line
			(start -0.12065 -0.2794)
			(end 0.12065 -0.2794)
			(stroke
				(width 0.1)
				(type default)
			)
			(layer "F.Fab")
		)
		(fp_line
			(start 0.12065 -0.2794)
			(end 0.12065 -0.3048)
			(stroke
				(width 0.1)
				(type default)
			)
			(layer "F.Fab")
		)
		(fp_line
			(start 0.12065 -0.3048)
			(end 0.67945 -0.3048)
			(stroke
				(width 0.1)
				(type default)
			)
			(layer "F.Fab")
		)
		(fp_line
			(start 0.67945 -0.3048)
			(end 0.67945 0.3048)
			(stroke
				(width 0.1)
				(type default)
			)
			(layer "F.Fab")
		)
		(fp_line
			(start -0.67945 -0.305054)
			(end -0.12065 -0.305054)
			(stroke
				(width 0.1)
				(type default)
			)
			(layer "F.Fab")
		)
		(fp_line
			(start -0.12065 -0.305054)
			(end -0.12065 -0.2794)
			(stroke
				(width 0.1)
				(type default)
			)
			(layer "F.Fab")
		)
		(pad "1" smd circle
			(at -0.40005 0 270)
			(size 0 0)
			(layers "F.Cu" "F.Mask" "F.Paste")
			(net "SSD10_CLK_EN_N")
		)
		(pad "2" smd circle
			(at 0.40005 0 270)
			(size 0 0)
			(layers "F.Cu" "F.Mask" "F.Paste")
			(net "SSD10_CLK_EN_R_N")
		)
	)
	(footprint ""
		(layer "F.Cu")
		(at 278.473916 -72.766682 90)
		(property "Reference" "PR7077"
			(at 0 0 90)
			(layer "F.SilkS")
			(hide yes)
			(effects
				(font
					(size 1.27 1.27)
				)
			)
		)
		(property "Value" ""
			(at 0 0 90)
			(layer "F.Fab")
			(effects
				(font
					(size 1.27 1.27)
				)
			)
		)
		(duplicate_pad_numbers_are_jumpers no)
		(fp_line
			(start 0.7874 -0.4064)
			(end 0.7874 0.4064)
			(stroke
				(width 0.1524)
				(type default)
			)
			(layer "F.SilkS")
		)
		(fp_line
			(start -0.7874 -0.4064)
			(end 0.7874 -0.4064)
			(stroke
				(width 0.1524)
				(type default)
			)
			(layer "F.SilkS")
		)
		(fp_line
			(start 0.7874 0.4064)
			(end -0.7874 0.4064)
			(stroke
				(width 0.1524)
				(type default)
			)
			(layer "F.SilkS")
		)
		(fp_line
			(start -0.7874 0.4064)
			(end -0.7874 -0.4064)
			(stroke
				(width 0.1524)
				(type default)
			)
			(layer "F.SilkS")
		)
		(fp_line
			(start -0.12065 -0.305054)
			(end -0.12065 -0.2794)
			(stroke
				(width 0.1)
				(type default)
			)
			(layer "F.Fab")
		)
		(fp_line
			(start -0.67945 -0.305054)
			(end -0.12065 -0.305054)
			(stroke
				(width 0.1)
				(type default)
			)
			(layer "F.Fab")
		)
		(fp_line
			(start 0.67945 -0.3048)
			(end 0.67945 0.3048)
			(stroke
				(width 0.1)
				(type default)
			)
			(layer "F.Fab")
		)
		(fp_line
			(start 0.12065 -0.3048)
			(end 0.67945 -0.3048)
			(stroke
				(width 0.1)
				(type default)
			)
			(layer "F.Fab")
		)
		(fp_line
			(start 0.12065 -0.2794)
			(end 0.12065 -0.3048)
			(stroke
				(width 0.1)
				(type default)
			)
			(layer "F.Fab")
		)
		(fp_line
			(start -0.12065 -0.2794)
			(end 0.12065 -0.2794)
			(stroke
				(width 0.1)
				(type default)
			)
			(layer "F.Fab")
		)
		(fp_line
			(start 0.120396 0.2794)
			(end -0.12065 0.2794)
			(stroke
				(width 0.1)
				(type default)
			)
			(layer "F.Fab")
		)
		(fp_line
			(start -0.12065 0.2794)
			(end -0.12065 0.3048)
			(stroke
				(width 0.1)
				(type default)
			)
			(layer "F.Fab")
		)
		(fp_line
			(start 0.67945 0.3048)
			(end 0.120396 0.3048)
			(stroke
				(width 0.1)
				(type default)
			)
			(layer "F.Fab")
		)
		(fp_line
			(start 0.120396 0.3048)
			(end 0.120396 0.2794)
			(stroke
				(width 0.1)
				(type default)
			)
			(layer "F.Fab")
		)
		(fp_line
			(start -0.12065 0.3048)
			(end -0.67945 0.3048)
			(stroke
				(width 0.1)
				(type default)
			)
			(layer "F.Fab")
		)
		(fp_line
			(start -0.67945 0.3048)
			(end -0.67945 -0.305054)
			(stroke
				(width 0.1)
				(type default)
			)
			(layer "F.Fab")
		)
		(pad "1" smd circle
			(at -0.40005 0 90)
			(size 0 0)
			(layers "F.Cu" "F.Mask" "F.Paste")
			(net "P12V_SSD9_CO_MODE")
		)
		(pad "2" smd circle
			(at 0.40005 0 90)
			(size 0 0)
			(layers "F.Cu" "F.Mask" "F.Paste")
			(net "GND")
		)
	)
	(footprint ""
		(layer "F.Cu")
		(at 291.194998 -103.814372 180)
		(property "Reference" "R273"
			(at 0 0 180)
			(layer "F.SilkS")
			(hide yes)
			(effects
				(font
					(size 1.27 1.27)
				)
			)
		)
		(property "Value" ""
			(at 0 0 180)
			(layer "F.Fab")
			(effects
				(font
					(size 1.27 1.27)
				)
			)
		)
		(duplicate_pad_numbers_are_jumpers no)
		(fp_line
			(start 0.7874 0.4064)
			(end -0.7874 0.4064)
			(stroke
				(width 0.1524)
				(type default)
			)
			(layer "F.SilkS")
		)
		(fp_line
			(start 0.7874 -0.4064)
			(end 0.7874 0.4064)
			(stroke
				(width 0.1524)
				(type default)
			)
			(layer "F.SilkS")
		)
		(fp_line
			(start -0.7874 0.4064)
			(end -0.7874 -0.4064)
			(stroke
				(width 0.1524)
				(type default)
			)
			(layer "F.SilkS")
		)
		(fp_line
			(start -0.7874 -0.4064)
			(end 0.7874 -0.4064)
			(stroke
				(width 0.1524)
				(type default)
			)
			(layer "F.SilkS")
		)
		(fp_line
			(start 0.67945 0.3048)
			(end 0.120396 0.3048)
			(stroke
				(width 0.1)
				(type default)
			)
			(layer "F.Fab")
		)
		(fp_line
			(start 0.67945 -0.3048)
			(end 0.67945 0.3048)
			(stroke
				(width 0.1)
				(type default)
			)
			(layer "F.Fab")
		)
		(fp_line
			(start 0.12065 -0.2794)
			(end 0.12065 -0.3048)
			(stroke
				(width 0.1)
				(type default)
			)
			(layer "F.Fab")
		)
		(fp_line
			(start 0.12065 -0.3048)
			(end 0.67945 -0.3048)
			(stroke
				(width 0.1)
				(type default)
			)
			(layer "F.Fab")
		)
		(fp_line
			(start 0.120396 0.3048)
			(end 0.120396 0.2794)
			(stroke
				(width 0.1)
				(type default)
			)
			(layer "F.Fab")
		)
		(fp_line
			(start 0.120396 0.2794)
			(end -0.12065 0.2794)
			(stroke
				(width 0.1)
				(type default)
			)
			(layer "F.Fab")
		)
		(fp_line
			(start -0.12065 0.3048)
			(end -0.67945 0.3048)
			(stroke
				(width 0.1)
				(type default)
			)
			(layer "F.Fab")
		)
		(fp_line
			(start -0.12065 0.2794)
			(end -0.12065 0.3048)
			(stroke
				(width 0.1)
				(type default)
			)
			(layer "F.Fab")
		)
		(fp_line
			(start -0.12065 -0.2794)
			(end 0.12065 -0.2794)
			(stroke
				(width 0.1)
				(type default)
			)
			(layer "F.Fab")
		)
		(fp_line
			(start -0.12065 -0.305054)
			(end -0.12065 -0.2794)
			(stroke
				(width 0.1)
				(type default)
			)
			(layer "F.Fab")
		)
		(fp_line
			(start -0.67945 0.3048)
			(end -0.67945 -0.305054)
			(stroke
				(width 0.1)
				(type default)
			)
			(layer "F.Fab")
		)
		(fp_line
			(start -0.67945 -0.305054)
			(end -0.12065 -0.305054)
			(stroke
				(width 0.1)
				(type default)
			)
			(layer "F.Fab")
		)
		(pad "1" smd circle
			(at -0.40005 0 180)
			(size 0 0)
			(layers "F.Cu" "F.Mask" "F.Paste")
			(net "NCSI_NIC5_TXD0")
		)
		(pad "2" smd circle
			(at 0.40005 0 180)
			(size 0 0)
			(layers "F.Cu" "F.Mask" "F.Paste")
			(net "GND")
		)
	)
	(footprint ""
		(layer "F.Cu")
		(at 173.750224 -50.96383 180)
		(property "Reference" "PC527"
			(at 0 0 180)
			(layer "F.SilkS")
			(hide yes)
			(effects
				(font
					(size 1.27 1.27)
				)
			)
		)
		(property "Value" ""
			(at 0 0 180)
			(layer "F.Fab")
			(effects
				(font
					(size 1.27 1.27)
				)
			)
		)
		(duplicate_pad_numbers_are_jumpers no)
		(fp_line
			(start 1.524 0.762)
			(end -1.524 0.762)
			(stroke
				(width 0.1524)
				(type default)
			)
			(layer "F.SilkS")
		)
		(fp_line
			(start 1.524 -0.762)
			(end 1.524 0.762)
			(stroke
				(width 0.1524)
				(type default)
			)
			(layer "F.SilkS")
		)
		(fp_line
			(start -1.524 0.762)
			(end -1.524 -0.762)
			(stroke
				(width 0.1524)
				(type default)
			)
			(layer "F.SilkS")
		)
		(fp_line
			(start -1.524 -0.762)
			(end 1.524 -0.762)
			(stroke
				(width 0.1524)
				(type default)
			)
			(layer "F.SilkS")
		)
		(fp_line
			(start 1.1049 0.724916)
			(end 1.1049 -0.724916)
			(stroke
				(width 0.1)
				(type default)
			)
			(layer "F.Fab")
		)
		(fp_line
			(start 1.1049 -0.724916)
			(end -1.1049 -0.724916)
			(stroke
				(width 0.1)
				(type default)
			)
			(layer "F.Fab")
		)
		(fp_line
			(start -1.1049 0.724916)
			(end 1.1049 0.724916)
			(stroke
				(width 0.1)
				(type default)
			)
			(layer "F.Fab")
		)
		(fp_line
			(start -1.1049 -0.724916)
			(end -1.1049 0.724916)
			(stroke
				(width 0.1)
				(type default)
			)
			(layer "F.Fab")
		)
		(pad "1" smd rect
			(at -0.889 0)
			(size 1.016 1.27)
			(layers "F.Cu" "F.Mask" "F.Paste")
			(net "P3V3_SSD6")
		)
		(pad "2" smd rect
			(at 0.889 0)
			(size 1.016 1.27)
			(layers "F.Cu" "F.Mask" "F.Paste")
			(net "GND")
		)
	)
	(footprint ""
		(layer "F.Cu")
		(at 197.739 -406.908 90)
		(property "Reference" "Q123"
			(at 0.822706 2.829052 0)
			(unlocked yes)
			(layer "F.SilkS")
			(effects
				(font
					(size 0.7874 0.5842)
					(thickness 0.1524)
				)
			)
		)
		(property "Value" ""
			(at 0 0 90)
			(layer "F.Fab")
			(effects
				(font
					(size 1.27 1.27)
				)
			)
		)
		(duplicate_pad_numbers_are_jumpers no)
		(fp_line
			(start 1.38176 -1.100074)
			(end 0.592074 -1.100074)
			(stroke
				(width 0.1524)
				(type default)
			)
			(layer "F.SilkS")
		)
		(fp_line
			(start 0.592074 -1.100074)
			(end 0 -0.508)
			(stroke
				(width 0.1524)
				(type default)
			)
			(layer "F.SilkS")
		)
		(fp_line
			(start -0.592074 -1.100074)
			(end -1.38176 -1.100074)
			(stroke
				(width 0.1524)
				(type default)
			)
			(layer "F.SilkS")
		)
		(fp_line
			(start -1.38176 -1.100074)
			(end -1.38176 1.100074)
			(stroke
				(width 0.1524)
				(type default)
			)
			(layer "F.SilkS")
		)
		(fp_line
			(start 0 -0.508)
			(end -0.592074 -1.100074)
			(stroke
				(width 0.1524)
				(type default)
			)
			(layer "F.SilkS")
		)
		(fp_line
			(start 1.38176 1.100074)
			(end 1.38176 -1.100074)
			(stroke
				(width 0.1524)
				(type default)
			)
			(layer "F.SilkS")
		)
		(fp_line
			(start -1.38176 1.100074)
			(end 1.38176 1.100074)
			(stroke
				(width 0.1524)
				(type default)
			)
			(layer "F.SilkS")
		)
		(fp_poly
			(pts
				(xy -1.70434 -1.32334) (xy -1.548384 -0.85598) (xy -2.015744 -1.011936)
			)
			(stroke
				(width 0)
				(type default)
			)
			(fill yes)
			(layer "F.SilkS")
		)
		(fp_line
			(start 0.674878 -1.100074)
			(end -0.674878 -1.100074)
			(stroke
				(width 0.1)
				(type default)
			)
			(layer "F.Fab")
		)
		(fp_line
			(start -0.674878 -1.100074)
			(end -0.674878 1.100074)
			(stroke
				(width 0.1)
				(type default)
			)
			(layer "F.Fab")
		)
		(fp_line
			(start 0.674878 1.100074)
			(end 0.674878 -1.100074)
			(stroke
				(width 0.1)
				(type default)
			)
			(layer "F.Fab")
		)
		(fp_line
			(start -0.674878 1.100074)
			(end 0.674878 1.100074)
			(stroke
				(width 0.1)
				(type default)
			)
			(layer "F.Fab")
		)
		(fp_poly
			(pts
				(xy -1.9431 -0.870204) (xy -1.50241 -0.649986) (xy -1.9431 -0.429768)
			)
			(stroke
				(width 0)
				(type default)
			)
			(fill yes)
			(layer "F.Fab")
		)
		(pad "1" smd rect
			(at -0.94996 -0.649986)
			(size 0.4318 0.6096)
			(layers "F.Cu" "F.Mask" "F.Paste")
			(net "GND")
		)
		(pad "2" smd rect
			(at -0.94996 0)
			(size 0.4318 0.6096)
			(layers "F.Cu" "F.Mask" "F.Paste")
			(net "MB_HSC_EN")
		)
		(pad "3" smd rect
			(at -0.94996 0.649986)
			(size 0.4318 0.6096)
			(layers "F.Cu" "F.Mask" "F.Paste")
			(net "MB_HSC_ISO_D2_EN")
		)
		(pad "4" smd rect
			(at 0.94996 0.649986)
			(size 0.4318 0.6096)
			(layers "F.Cu" "F.Mask" "F.Paste")
			(net "GND")
		)
		(pad "5" smd rect
			(at 0.94996 0)
			(size 0.4318 0.6096)
			(layers "F.Cu" "F.Mask" "F.Paste")
			(net "MB_HSC_ISO_D1_EN")
		)
		(pad "6" smd rect
			(at 0.94996 -0.649986)
			(size 0.4318 0.6096)
			(layers "F.Cu" "F.Mask" "F.Paste")
			(net "MB_HSC_ISO_D1_EN")
		)
	)
	(footprint ""
		(layer "F.Cu")
		(at 288.079942 -141.9352 180)
		(property "Reference" "R214"
			(at 0 0 180)
			(layer "F.SilkS")
			(hide yes)
			(effects
				(font
					(size 1.27 1.27)
				)
			)
		)
		(property "Value" ""
			(at 0 0 180)
			(layer "F.Fab")
			(effects
				(font
					(size 1.27 1.27)
				)
			)
		)
		(duplicate_pad_numbers_are_jumpers no)
		(fp_line
			(start 0.7874 0.4064)
			(end -0.7874 0.4064)
			(stroke
				(width 0.1524)
				(type default)
			)
			(layer "F.SilkS")
		)
		(fp_line
			(start 0.7874 -0.4064)
			(end 0.7874 0.4064)
			(stroke
				(width 0.1524)
				(type default)
			)
			(layer "F.SilkS")
		)
		(fp_line
			(start -0.7874 0.4064)
			(end -0.7874 -0.4064)
			(stroke
				(width 0.1524)
				(type default)
			)
			(layer "F.SilkS")
		)
		(fp_line
			(start -0.7874 -0.4064)
			(end 0.7874 -0.4064)
			(stroke
				(width 0.1524)
				(type default)
			)
			(layer "F.SilkS")
		)
		(fp_line
			(start 0.67945 0.3048)
			(end 0.120396 0.3048)
			(stroke
				(width 0.1)
				(type default)
			)
			(layer "F.Fab")
		)
		(fp_line
			(start 0.67945 -0.3048)
			(end 0.67945 0.3048)
			(stroke
				(width 0.1)
				(type default)
			)
			(layer "F.Fab")
		)
		(fp_line
			(start 0.12065 -0.2794)
			(end 0.12065 -0.3048)
			(stroke
				(width 0.1)
				(type default)
			)
			(layer "F.Fab")
		)
		(fp_line
			(start 0.12065 -0.3048)
			(end 0.67945 -0.3048)
			(stroke
				(width 0.1)
				(type default)
			)
			(layer "F.Fab")
		)
		(fp_line
			(start 0.120396 0.3048)
			(end 0.120396 0.2794)
			(stroke
				(width 0.1)
				(type default)
			)
			(layer "F.Fab")
		)
		(fp_line
			(start 0.120396 0.2794)
			(end -0.12065 0.2794)
			(stroke
				(width 0.1)
				(type default)
			)
			(layer "F.Fab")
		)
		(fp_line
			(start -0.12065 0.3048)
			(end -0.67945 0.3048)
			(stroke
				(width 0.1)
				(type default)
			)
			(layer "F.Fab")
		)
		(fp_line
			(start -0.12065 0.2794)
			(end -0.12065 0.3048)
			(stroke
				(width 0.1)
				(type default)
			)
			(layer "F.Fab")
		)
		(fp_line
			(start -0.12065 -0.2794)
			(end 0.12065 -0.2794)
			(stroke
				(width 0.1)
				(type default)
			)
			(layer "F.Fab")
		)
		(fp_line
			(start -0.12065 -0.305054)
			(end -0.12065 -0.2794)
			(stroke
				(width 0.1)
				(type default)
			)
			(layer "F.Fab")
		)
		(fp_line
			(start -0.67945 0.3048)
			(end -0.67945 -0.305054)
			(stroke
				(width 0.1)
				(type default)
			)
			(layer "F.Fab")
		)
		(fp_line
			(start -0.67945 -0.305054)
			(end -0.12065 -0.305054)
			(stroke
				(width 0.1)
				(type default)
			)
			(layer "F.Fab")
		)
		(pad "1" smd circle
			(at -0.40005 0 180)
			(size 0 0)
			(layers "F.Cu" "F.Mask" "F.Paste")
			(net "P3V3_NIC4")
		)
		(pad "2" smd circle
			(at 0.40005 0 180)
			(size 0 0)
			(layers "F.Cu" "F.Mask" "F.Paste")
			(net "SMB_NIC4_LS_SDA")
		)
	)
)
